(kicad_pcb
	(version 20260206)
	(generator "pcbnew")
	(generator_version "10.0")
	(general
		(thickness 1.6)
		(legacy_teardrops no)
	)
	(paper "A4")
	(title_block
		(title "04192023_DAF0TMB3IC0_F0TG_MB_C_brd_V02_OCP.brd")
		(comment 1 "Grand Teton / footprints 3827-3827 of 8354")
	)
	(layers
		(0 "F.Cu" signal "TOP")
		(4 "In1.Cu" signal "GND")
		(6 "In2.Cu" signal "IN1")
		(8 "In3.Cu" signal "GND1")
		(10 "In4.Cu" signal "IN2")
		(12 "In5.Cu" signal "GND2")
		(14 "In6.Cu" signal "IN3")
		(16 "In7.Cu" signal "GND3")
		(18 "In8.Cu" signal "VCC")
		(20 "In9.Cu" signal "VCC1")
		(22 "In10.Cu" signal "GND4")
		(24 "In11.Cu" signal "IN4")
		(26 "In12.Cu" signal "GND5")
		(28 "In13.Cu" signal "IN5")
		(30 "In14.Cu" signal "GND6")
		(32 "In15.Cu" signal "IN6")
		(34 "In16.Cu" signal "GND7")
		(2 "B.Cu" signal "BOTTOM")
		(9 "F.Adhes" user "F.Adhesive")
		(11 "B.Adhes" user "B.Adhesive")
		(13 "F.Paste" user "Package Geometry/Pastemask Top")
		(15 "B.Paste" user "Package Geometry/Pastemask Bottom")
		(5 "F.SilkS" user "Ref Des/Silkscreen Top")
		(7 "B.SilkS" user "Ref Des/Silkscreen Bottom")
		(1 "F.Mask" user "Board Geometry/Soldermask Top")
		(3 "B.Mask" user "Board Geometry/Soldermask Bottom")
		(17 "Dwgs.User" user "User.Drawings")
		(19 "Cmts.User" user "User.Comments")
		(21 "Eco1.User" user "User.Eco1")
		(23 "Eco2.User" user "User.Eco2")
		(25 "Edge.Cuts" user "Board Geometry/Outline")
		(27 "Margin" user)
		(31 "F.CrtYd" user "Package Geometry/Place Bound Top")
		(29 "B.CrtYd" user "Package Geometry/Place Bound Bottom")
		(35 "F.Fab" user "Ref Des/Assembly Top")
		(33 "B.Fab" user "Ref Des/Assembly Bottom")
	)
	(footprint ""
		(layer "F.Cu")
		(at 356.69601 -402.7424 -90)
		(property "Reference" "R1019"
			(at 0 0 270)
			(layer "F.SilkS")
			(hide yes)
			(effects
				(font
					(size 1.27 1.27)
				)
			)
		)
		(property "Value" ""
			(at 0 0 270)
			(layer "F.Fab")
			(effects
				(font
					(size 1.27 1.27)
				)
			)
		)
		(duplicate_pad_numbers_are_jumpers no)
		(fp_line
			(start -0.32512 0.175006)
			(end -0.32512 -0.175006)
			(stroke
				(width 0.1)
				(type default)
			)
			(layer "F.Fab")
		)
		(fp_line
			(start 0.32512 0.175006)
			(end -0.32512 0.175006)
			(stroke
				(width 0.1)
				(type default)
			)
			(layer "F.Fab")
		)
		(fp_line
			(start -0.32512 -0.175006)
			(end 0.32512 -0.175006)
			(stroke
				(width 0.1)
				(type default)
			)
			(layer "F.Fab")
		)
		(fp_line
			(start 0.32512 -0.175006)
			(end 0.32512 0.175006)
			(stroke
				(width 0.1)
				(type default)
			)
			(layer "F.Fab")
		)
		(pad "1" smd rect
			(at -0.2667 0 270)
			(size 0.3048 0.381)
			(layers "F.Cu" "F.Mask" "F.Paste")
			(net "RST_RT_CPU0_P1_PERST_R_N")
		)
		(pad "2" smd rect
			(at 0.2667 0 90)
			(size 0.3048 0.381)
			(layers "F.Cu" "F.Mask" "F.Paste")
			(net "GND")
		)
	)
)
